(kicad_pcb
	(version 20260206)
	(generator "pcbnew")
	(generator_version "10.0")
	(general
		(thickness 1.6)
		(legacy_teardrops no)
	)
	(paper "A4")
	(title_block
		(title "03242023_DA0F0TMBIJ0_F0T_Motherboard_J_brd_V01_OCP.brd")
		(comment 1 "Grand Teton / footprints 1220-1226 of 6105")
	)
	(layers
		(0 "F.Cu" signal "TOP")
		(4 "In1.Cu" signal "GND")
		(6 "In2.Cu" signal "IN1")
		(8 "In3.Cu" signal "GND1")
		(10 "In4.Cu" signal "IN2")
		(12 "In5.Cu" signal "GND2")
		(14 "In6.Cu" signal "IN3")
		(16 "In7.Cu" signal "GND3")
		(18 "In8.Cu" signal "VCC")
		(20 "In9.Cu" signal "VCC1")
		(22 "In10.Cu" signal "GND4")
		(24 "In11.Cu" signal "IN4")
		(26 "In12.Cu" signal "GND5")
		(28 "In13.Cu" signal "IN5")
		(30 "In14.Cu" signal "GND6")
		(32 "In15.Cu" signal "IN6")
		(34 "In16.Cu" signal "GND7")
		(2 "B.Cu" signal "BOTTOM")
		(9 "F.Adhes" user "F.Adhesive")
		(11 "B.Adhes" user "B.Adhesive")
		(13 "F.Paste" user "Package Geometry/Pastemask Top")
		(15 "B.Paste" user "Package Geometry/Pastemask Bottom")
		(5 "F.SilkS" user "Ref Des/Silkscreen Top")
		(7 "B.SilkS" user "Ref Des/Silkscreen Bottom")
		(1 "F.Mask" user "Board Geometry/Soldermask Top")
		(3 "B.Mask" user "Board Geometry/Soldermask Bottom")
		(17 "Dwgs.User" user "User.Drawings")
		(19 "Cmts.User" user "User.Comments")
		(21 "Eco1.User" user "User.Eco1")
		(23 "Eco2.User" user "User.Eco2")
		(25 "Edge.Cuts" user "Board Geometry/Outline")
		(27 "Margin" user)
		(31 "F.CrtYd" user "Package Geometry/Place Bound Top")
		(29 "B.CrtYd" user "Package Geometry/Place Bound Bottom")
		(35 "F.Fab" user "Ref Des/Assembly Top")
		(33 "B.Fab" user "Ref Des/Assembly Bottom")
	)
	(footprint ""
		(layer "F.Cu")
		(at 355.2698 -406.852628 -90)
		(property "Reference" "R4548"
			(at 0 0 270)
			(layer "F.SilkS")
			(hide yes)
			(effects
				(font
					(size 1.27 1.27)
				)
			)
		)
		(property "Value" ""
			(at 0 0 270)
			(layer "F.Fab")
			(effects
				(font
					(size 1.27 1.27)
				)
			)
		)
		(duplicate_pad_numbers_are_jumpers no)
		(fp_line
			(start -0.7874 0.4064)
			(end -0.7874 -0.4064)
			(stroke
				(width 0.1524)
				(type default)
			)
			(layer "F.SilkS")
		)
		(fp_line
			(start 0.7874 0.4064)
			(end -0.7874 0.4064)
			(stroke
				(width 0.1524)
				(type default)
			)
			(layer "F.SilkS")
		)
		(fp_line
			(start -0.7874 -0.4064)
			(end 0.7874 -0.4064)
			(stroke
				(width 0.1524)
				(type default)
			)
			(layer "F.SilkS")
		)
		(fp_line
			(start 0.7874 -0.4064)
			(end 0.7874 0.4064)
			(stroke
				(width 0.1524)
				(type default)
			)
			(layer "F.SilkS")
		)
		(fp_line
			(start -0.67945 0.3048)
			(end -0.67945 -0.305054)
			(stroke
				(width 0.1)
				(type default)
			)
			(layer "F.Fab")
		)
		(fp_line
			(start -0.12065 0.3048)
			(end -0.67945 0.3048)
			(stroke
				(width 0.1)
				(type default)
			)
			(layer "F.Fab")
		)
		(fp_line
			(start 0.120396 0.3048)
			(end 0.120396 0.2794)
			(stroke
				(width 0.1)
				(type default)
			)
			(layer "F.Fab")
		)
		(fp_line
			(start 0.67945 0.3048)
			(end 0.120396 0.3048)
			(stroke
				(width 0.1)
				(type default)
			)
			(layer "F.Fab")
		)
		(fp_line
			(start -0.12065 0.2794)
			(end -0.12065 0.3048)
			(stroke
				(width 0.1)
				(type default)
			)
			(layer "F.Fab")
		)
		(fp_line
			(start 0.120396 0.2794)
			(end -0.12065 0.2794)
			(stroke
				(width 0.1)
				(type default)
			)
			(layer "F.Fab")
		)
		(fp_line
			(start -0.12065 -0.2794)
			(end 0.12065 -0.2794)
			(stroke
				(width 0.1)
				(type default)
			)
			(layer "F.Fab")
		)
		(fp_line
			(start 0.12065 -0.2794)
			(end 0.12065 -0.3048)
			(stroke
				(width 0.1)
				(type default)
			)
			(layer "F.Fab")
		)
		(fp_line
			(start 0.12065 -0.3048)
			(end 0.67945 -0.3048)
			(stroke
				(width 0.1)
				(type default)
			)
			(layer "F.Fab")
		)
		(fp_line
			(start 0.67945 -0.3048)
			(end 0.67945 0.3048)
			(stroke
				(width 0.1)
				(type default)
			)
			(layer "F.Fab")
		)
		(fp_line
			(start -0.67945 -0.305054)
			(end -0.12065 -0.305054)
			(stroke
				(width 0.1)
				(type default)
			)
			(layer "F.Fab")
		)
		(fp_line
			(start -0.12065 -0.305054)
			(end -0.12065 -0.2794)
			(stroke
				(width 0.1)
				(type default)
			)
			(layer "F.Fab")
		)
		(pad "1" smd circle
			(at -0.40005 0 270)
			(size 0 0)
			(layers "F.Cu" "F.Mask" "F.Paste")
			(net "SWB_HSC_EN")
		)
		(pad "2" smd circle
			(at 0.40005 0 270)
			(size 0 0)
			(layers "F.Cu" "F.Mask" "F.Paste")
			(net "GND")
		)
	)
	(footprint ""
		(layer "F.Cu")
		(at 357.735632 -398.789398)
		(property "Reference" "R2670"
			(at 0 0 0)
			(layer "F.SilkS")
			(hide yes)
			(effects
				(font
					(size 1.27 1.27)
				)
			)
		)
		(property "Value" ""
			(at 0 0 0)
			(layer "F.Fab")
			(effects
				(font
					(size 1.27 1.27)
				)
			)
		)
		(duplicate_pad_numbers_are_jumpers no)
		(fp_line
			(start -0.7874 -0.4064)
			(end 0.7874 -0.4064)
			(stroke
				(width 0.1524)
				(type default)
			)
			(layer "F.SilkS")
		)
		(fp_line
			(start -0.7874 0.4064)
			(end -0.7874 -0.4064)
			(stroke
				(width 0.1524)
				(type default)
			)
			(layer "F.SilkS")
		)
		(fp_line
			(start 0.7874 -0.4064)
			(end 0.7874 0.4064)
			(stroke
				(width 0.1524)
				(type default)
			)
			(layer "F.SilkS")
		)
		(fp_line
			(start 0.7874 0.4064)
			(end -0.7874 0.4064)
			(stroke
				(width 0.1524)
				(type default)
			)
			(layer "F.SilkS")
		)
		(fp_line
			(start -0.67945 -0.305054)
			(end -0.12065 -0.305054)
			(stroke
				(width 0.1)
				(type default)
			)
			(layer "F.Fab")
		)
		(fp_line
			(start -0.67945 0.3048)
			(end -0.67945 -0.305054)
			(stroke
				(width 0.1)
				(type default)
			)
			(layer "F.Fab")
		)
		(fp_line
			(start -0.12065 -0.305054)
			(end -0.12065 -0.2794)
			(stroke
				(width 0.1)
				(type default)
			)
			(layer "F.Fab")
		)
		(fp_line
			(start -0.12065 -0.2794)
			(end 0.12065 -0.2794)
			(stroke
				(width 0.1)
				(type default)
			)
			(layer "F.Fab")
		)
		(fp_line
			(start -0.12065 0.2794)
			(end -0.12065 0.3048)
			(stroke
				(width 0.1)
				(type default)
			)
			(layer "F.Fab")
		)
		(fp_line
			(start -0.12065 0.3048)
			(end -0.67945 0.3048)
			(stroke
				(width 0.1)
				(type default)
			)
			(layer "F.Fab")
		)
		(fp_line
			(start 0.120396 0.2794)
			(end -0.12065 0.2794)
			(stroke
				(width 0.1)
				(type default)
			)
			(layer "F.Fab")
		)
		(fp_line
			(start 0.120396 0.3048)
			(end 0.120396 0.2794)
			(stroke
				(width 0.1)
				(type default)
			)
			(layer "F.Fab")
		)
		(fp_line
			(start 0.12065 -0.3048)
			(end 0.67945 -0.3048)
			(stroke
				(width 0.1)
				(type default)
			)
			(layer "F.Fab")
		)
		(fp_line
			(start 0.12065 -0.2794)
			(end 0.12065 -0.3048)
			(stroke
				(width 0.1)
				(type default)
			)
			(layer "F.Fab")
		)
		(fp_line
			(start 0.67945 -0.3048)
			(end 0.67945 0.3048)
			(stroke
				(width 0.1)
				(type default)
			)
			(layer "F.Fab")
		)
		(fp_line
			(start 0.67945 0.3048)
			(end 0.120396 0.3048)
			(stroke
				(width 0.1)
				(type default)
			)
			(layer "F.Fab")
		)
		(pad "1" smd circle
			(at -0.40005 0)
			(size 0 0)
			(layers "F.Cu" "F.Mask" "F.Paste")
			(net "P3V3_AUX")
		)
		(pad "2" smd circle
			(at 0.40005 0)
			(size 0 0)
			(layers "F.Cu" "F.Mask" "F.Paste")
			(net "I3C_BMC_SWB_BUF_R_SCL")
		)
	)
	(footprint ""
		(layer "F.Cu")
		(at 307.363622 -44.948348 180)
		(property "Reference" "R608"
			(at 0 0 180)
			(layer "F.SilkS")
			(hide yes)
			(effects
				(font
					(size 1.27 1.27)
				)
			)
		)
		(property "Value" ""
			(at 0 0 180)
			(layer "F.Fab")
			(effects
				(font
					(size 1.27 1.27)
				)
			)
		)
		(duplicate_pad_numbers_are_jumpers no)
		(fp_line
			(start 0.7874 0.4064)
			(end -0.7874 0.4064)
			(stroke
				(width 0.1524)
				(type default)
			)
			(layer "F.SilkS")
		)
		(fp_line
			(start 0.7874 -0.4064)
			(end 0.7874 0.4064)
			(stroke
				(width 0.1524)
				(type default)
			)
			(layer "F.SilkS")
		)
		(fp_line
			(start -0.7874 0.4064)
			(end -0.7874 -0.4064)
			(stroke
				(width 0.1524)
				(type default)
			)
			(layer "F.SilkS")
		)
		(fp_line
			(start -0.7874 -0.4064)
			(end 0.7874 -0.4064)
			(stroke
				(width 0.1524)
				(type default)
			)
			(layer "F.SilkS")
		)
		(fp_line
			(start 0.67945 0.3048)
			(end 0.120396 0.3048)
			(stroke
				(width 0.1)
				(type default)
			)
			(layer "F.Fab")
		)
		(fp_line
			(start 0.67945 -0.3048)
			(end 0.67945 0.3048)
			(stroke
				(width 0.1)
				(type default)
			)
			(layer "F.Fab")
		)
		(fp_line
			(start 0.12065 -0.2794)
			(end 0.12065 -0.3048)
			(stroke
				(width 0.1)
				(type default)
			)
			(layer "F.Fab")
		)
		(fp_line
			(start 0.12065 -0.3048)
			(end 0.67945 -0.3048)
			(stroke
				(width 0.1)
				(type default)
			)
			(layer "F.Fab")
		)
		(fp_line
			(start 0.120396 0.3048)
			(end 0.120396 0.2794)
			(stroke
				(width 0.1)
				(type default)
			)
			(layer "F.Fab")
		)
		(fp_line
			(start 0.120396 0.2794)
			(end -0.12065 0.2794)
			(stroke
				(width 0.1)
				(type default)
			)
			(layer "F.Fab")
		)
		(fp_line
			(start -0.12065 0.3048)
			(end -0.67945 0.3048)
			(stroke
				(width 0.1)
				(type default)
			)
			(layer "F.Fab")
		)
		(fp_line
			(start -0.12065 0.2794)
			(end -0.12065 0.3048)
			(stroke
				(width 0.1)
				(type default)
			)
			(layer "F.Fab")
		)
		(fp_line
			(start -0.12065 -0.2794)
			(end 0.12065 -0.2794)
			(stroke
				(width 0.1)
				(type default)
			)
			(layer "F.Fab")
		)
		(fp_line
			(start -0.12065 -0.305054)
			(end -0.12065 -0.2794)
			(stroke
				(width 0.1)
				(type default)
			)
			(layer "F.Fab")
		)
		(fp_line
			(start -0.67945 0.3048)
			(end -0.67945 -0.305054)
			(stroke
				(width 0.1)
				(type default)
			)
			(layer "F.Fab")
		)
		(fp_line
			(start -0.67945 -0.305054)
			(end -0.12065 -0.305054)
			(stroke
				(width 0.1)
				(type default)
			)
			(layer "F.Fab")
		)
		(pad "1" smd circle
			(at -0.40005 0 180)
			(size 0 0)
			(layers "F.Cu" "F.Mask" "F.Paste")
			(net "FM_ESPI_FLASH_MODE")
		)
		(pad "2" smd circle
			(at 0.40005 0 180)
			(size 0 0)
			(layers "F.Cu" "F.Mask" "F.Paste")
			(net "GND")
		)
	)
	(footprint ""
		(layer "F.Cu")
		(at 404.900384 -17.612614 90)
		(property "Reference" "C849"
			(at 0 0 90)
			(layer "F.SilkS")
			(hide yes)
			(effects
				(font
					(size 1.27 1.27)
				)
			)
		)
		(property "Value" ""
			(at 0 0 90)
			(layer "F.Fab")
			(effects
				(font
					(size 1.27 1.27)
				)
			)
		)
		(duplicate_pad_numbers_are_jumpers no)
		(fp_line
			(start 0.299974 -0.150114)
			(end 0.299974 0.150114)
			(stroke
				(width 0.1)
				(type default)
			)
			(layer "F.Fab")
		)
		(fp_line
			(start -0.299974 -0.150114)
			(end 0.299974 -0.150114)
			(stroke
				(width 0.1)
				(type default)
			)
			(layer "F.Fab")
		)
		(fp_line
			(start 0.299974 0.150114)
			(end -0.299974 0.150114)
			(stroke
				(width 0.1)
				(type default)
			)
			(layer "F.Fab")
		)
		(fp_line
			(start -0.299974 0.150114)
			(end -0.299974 -0.150114)
			(stroke
				(width 0.1)
				(type default)
			)
			(layer "F.Fab")
		)
		(pad "1" smd rect
			(at -0.2667 0 90)
			(size 0.3048 0.381)
			(layers "F.Cu" "F.Mask" "F.Paste")
			(net "P5E_CPU0_PE1_TX_C_DP<10>")
		)
		(pad "2" smd rect
			(at 0.2667 0 90)
			(size 0.3048 0.381)
			(layers "F.Cu" "F.Mask" "F.Paste")
			(net "P5E_CPU0_PE1_TX_DP<10>")
		)
	)
	(footprint ""
		(layer "F.Cu")
		(at 213.4108 -107.4166 -90)
		(property "Reference" "R4777"
			(at 0 0 270)
			(layer "F.SilkS")
			(hide yes)
			(effects
				(font
					(size 1.27 1.27)
				)
			)
		)
		(property "Value" ""
			(at 0 0 270)
			(layer "F.Fab")
			(effects
				(font
					(size 1.27 1.27)
				)
			)
		)
		(duplicate_pad_numbers_are_jumpers no)
		(fp_line
			(start -0.7874 0.4064)
			(end -0.7874 -0.4064)
			(stroke
				(width 0.1524)
				(type default)
			)
			(layer "F.SilkS")
		)
		(fp_line
			(start 0.7874 0.4064)
			(end -0.7874 0.4064)
			(stroke
				(width 0.1524)
				(type default)
			)
			(layer "F.SilkS")
		)
		(fp_line
			(start -0.7874 -0.4064)
			(end 0.7874 -0.4064)
			(stroke
				(width 0.1524)
				(type default)
			)
			(layer "F.SilkS")
		)
		(fp_line
			(start 0.7874 -0.4064)
			(end 0.7874 0.4064)
			(stroke
				(width 0.1524)
				(type default)
			)
			(layer "F.SilkS")
		)
		(fp_line
			(start -0.67945 0.3048)
			(end -0.67945 -0.305054)
			(stroke
				(width 0.1)
				(type default)
			)
			(layer "F.Fab")
		)
		(fp_line
			(start -0.12065 0.3048)
			(end -0.67945 0.3048)
			(stroke
				(width 0.1)
				(type default)
			)
			(layer "F.Fab")
		)
		(fp_line
			(start 0.120396 0.3048)
			(end 0.120396 0.2794)
			(stroke
				(width 0.1)
				(type default)
			)
			(layer "F.Fab")
		)
		(fp_line
			(start 0.67945 0.3048)
			(end 0.120396 0.3048)
			(stroke
				(width 0.1)
				(type default)
			)
			(layer "F.Fab")
		)
		(fp_line
			(start -0.12065 0.2794)
			(end -0.12065 0.3048)
			(stroke
				(width 0.1)
				(type default)
			)
			(layer "F.Fab")
		)
		(fp_line
			(start 0.120396 0.2794)
			(end -0.12065 0.2794)
			(stroke
				(width 0.1)
				(type default)
			)
			(layer "F.Fab")
		)
		(fp_line
			(start -0.12065 -0.2794)
			(end 0.12065 -0.2794)
			(stroke
				(width 0.1)
				(type default)
			)
			(layer "F.Fab")
		)
		(fp_line
			(start 0.12065 -0.2794)
			(end 0.12065 -0.3048)
			(stroke
				(width 0.1)
				(type default)
			)
			(layer "F.Fab")
		)
		(fp_line
			(start 0.12065 -0.3048)
			(end 0.67945 -0.3048)
			(stroke
				(width 0.1)
				(type default)
			)
			(layer "F.Fab")
		)
		(fp_line
			(start 0.67945 -0.3048)
			(end 0.67945 0.3048)
			(stroke
				(width 0.1)
				(type default)
			)
			(layer "F.Fab")
		)
		(fp_line
			(start -0.67945 -0.305054)
			(end -0.12065 -0.305054)
			(stroke
				(width 0.1)
				(type default)
			)
			(layer "F.Fab")
		)
		(fp_line
			(start -0.12065 -0.305054)
			(end -0.12065 -0.2794)
			(stroke
				(width 0.1)
				(type default)
			)
			(layer "F.Fab")
		)
		(pad "1" smd circle
			(at -0.40005 0 270)
			(size 0 0)
			(layers "F.Cu" "F.Mask" "F.Paste")
			(net "P12V_AUX_UV_TRIGGER")
		)
		(pad "2" smd circle
			(at 0.40005 0 270)
			(size 0 0)
			(layers "F.Cu" "F.Mask" "F.Paste")
			(net "GND")
		)
	)
	(footprint ""
		(layer "F.Cu")
		(at 241.314986 -107.771692 180)
		(property "Reference" "R1012"
			(at 0 0 180)
			(layer "F.SilkS")
			(hide yes)
			(effects
				(font
					(size 1.27 1.27)
				)
			)
		)
		(property "Value" ""
			(at 0 0 180)
			(layer "F.Fab")
			(effects
				(font
					(size 1.27 1.27)
				)
			)
		)
		(duplicate_pad_numbers_are_jumpers no)
		(fp_line
			(start 0.7874 0.4064)
			(end -0.7874 0.4064)
			(stroke
				(width 0.1524)
				(type default)
			)
			(layer "F.SilkS")
		)
		(fp_line
			(start 0.7874 -0.4064)
			(end 0.7874 0.4064)
			(stroke
				(width 0.1524)
				(type default)
			)
			(layer "F.SilkS")
		)
		(fp_line
			(start -0.7874 0.4064)
			(end -0.7874 -0.4064)
			(stroke
				(width 0.1524)
				(type default)
			)
			(layer "F.SilkS")
		)
		(fp_line
			(start -0.7874 -0.4064)
			(end 0.7874 -0.4064)
			(stroke
				(width 0.1524)
				(type default)
			)
			(layer "F.SilkS")
		)
		(fp_line
			(start 0.67945 0.3048)
			(end 0.120396 0.3048)
			(stroke
				(width 0.1)
				(type default)
			)
			(layer "F.Fab")
		)
		(fp_line
			(start 0.67945 -0.3048)
			(end 0.67945 0.3048)
			(stroke
				(width 0.1)
				(type default)
			)
			(layer "F.Fab")
		)
		(fp_line
			(start 0.12065 -0.2794)
			(end 0.12065 -0.3048)
			(stroke
				(width 0.1)
				(type default)
			)
			(layer "F.Fab")
		)
		(fp_line
			(start 0.12065 -0.3048)
			(end 0.67945 -0.3048)
			(stroke
				(width 0.1)
				(type default)
			)
			(layer "F.Fab")
		)
		(fp_line
			(start 0.120396 0.3048)
			(end 0.120396 0.2794)
			(stroke
				(width 0.1)
				(type default)
			)
			(layer "F.Fab")
		)
		(fp_line
			(start 0.120396 0.2794)
			(end -0.12065 0.2794)
			(stroke
				(width 0.1)
				(type default)
			)
			(layer "F.Fab")
		)
		(fp_line
			(start -0.12065 0.3048)
			(end -0.67945 0.3048)
			(stroke
				(width 0.1)
				(type default)
			)
			(layer "F.Fab")
		)
		(fp_line
			(start -0.12065 0.2794)
			(end -0.12065 0.3048)
			(stroke
				(width 0.1)
				(type default)
			)
			(layer "F.Fab")
		)
		(fp_line
			(start -0.12065 -0.2794)
			(end 0.12065 -0.2794)
			(stroke
				(width 0.1)
				(type default)
			)
			(layer "F.Fab")
		)
		(fp_line
			(start -0.12065 -0.305054)
			(end -0.12065 -0.2794)
			(stroke
				(width 0.1)
				(type default)
			)
			(layer "F.Fab")
		)
		(fp_line
			(start -0.67945 0.3048)
			(end -0.67945 -0.305054)
			(stroke
				(width 0.1)
				(type default)
			)
			(layer "F.Fab")
		)
		(fp_line
			(start -0.67945 -0.305054)
			(end -0.12065 -0.305054)
			(stroke
				(width 0.1)
				(type default)
			)
			(layer "F.Fab")
		)
		(pad "1" smd circle
			(at -0.40005 0 180)
			(size 0 0)
			(layers "F.Cu" "F.Mask" "F.Paste")
			(net "CLK_25M_CK440_CPU0_DP")
		)
		(pad "2" smd circle
			(at 0.40005 0 180)
			(size 0 0)
			(layers "F.Cu" "F.Mask" "F.Paste")
			(net "CLK_25M_CK440_CPU0_R_DP")
		)
	)
	(footprint ""
		(layer "F.Cu")
		(at 349.014034 -69.13118)
		(property "Reference" "C148"
			(at 0 0 0)
			(layer "F.SilkS")
			(hide yes)
			(effects
				(font
					(size 1.27 1.27)
				)
			)
		)
		(property "Value" ""
			(at 0 0 0)
			(layer "F.Fab")
			(effects
				(font
					(size 1.27 1.27)
				)
			)
		)
		(duplicate_pad_numbers_are_jumpers no)
		(fp_line
			(start -0.299974 -0.150114)
			(end 0.299974 -0.150114)
			(stroke
				(width 0.1)
				(type default)
			)
			(layer "F.Fab")
		)
		(fp_line
			(start -0.299974 0.150114)
			(end -0.299974 -0.150114)
			(stroke
				(width 0.1)
				(type default)
			)
			(layer "F.Fab")
		)
		(fp_line
			(start 0.299974 -0.150114)
			(end 0.299974 0.150114)
			(stroke
				(width 0.1)
				(type default)
			)
			(layer "F.Fab")
		)
		(fp_line
			(start 0.299974 0.150114)
			(end -0.299974 0.150114)
			(stroke
				(width 0.1)
				(type default)
			)
			(layer "F.Fab")
		)
		(pad "1" smd rect
			(at -0.2667 0)
			(size 0.3048 0.381)
			(layers "F.Cu" "F.Mask" "F.Paste")
			(net "DMI_CPU0_PCH_TX_C_DP<3>")
		)
		(pad "2" smd rect
			(at 0.2667 0)
			(size 0.3048 0.381)
			(layers "F.Cu" "F.Mask" "F.Paste")
			(net "DMI_CPU0_PCH_TX_DP<3>")
		)
		(zone
			(layer "In1.Cu")
			(hatch none 0.5)
			(connect_pads
				(clearance 0)
			)
			(min_thickness 0.25)
			(keepout
				(tracks not_allowed)
				(vias allowed)
				(pads allowed)
				(copperpour not_allowed)
				(footprints allowed)
			)
			(placement
				(enabled no)
				(sheetname "")
			)
			(fill
				(thermal_gap 0.5)
				(thermal_bridge_width 0.5)
				(island_removal_mode 0)
			)
			(polygon
				(pts
					(arc
						(start 348.620334 -68.88988)
						(mid 348.566452 -68.912198)
						(end 348.544134 -68.96608)
					)
					(arc
						(start 348.544134 -69.29628)
						(mid 348.566452 -69.350162)
						(end 348.620334 -69.37248)
					)
					(arc
						(start 348.874334 -69.37248)
						(mid 348.928216 -69.350162)
						(end 348.950534 -69.29628)
					)
					(arc
						(start 348.950534 -68.96608)
						(mid 348.928216 -68.912198)
						(end 348.874334 -68.88988)
					)
				)
			)
		)
		(zone
			(layer "In1.Cu")
			(hatch none 0.5)
			(connect_pads
				(clearance 0)
			)
			(min_thickness 0.25)
			(keepout
				(tracks not_allowed)
				(vias allowed)
				(pads allowed)
				(copperpour not_allowed)
				(footprints allowed)
			)
			(placement
				(enabled no)
				(sheetname "")
			)
			(fill
				(thermal_gap 0.5)
				(thermal_bridge_width 0.5)
				(island_removal_mode 0)
			)
			(polygon
				(pts
					(arc
						(start 349.153734 -68.88988)
						(mid 349.099852 -68.912198)
						(end 349.077534 -68.96608)
					)
					(arc
						(start 349.077534 -69.29628)
						(mid 349.099852 -69.350162)
						(end 349.153734 -69.37248)
					)
					(arc
						(start 349.407734 -69.37248)
						(mid 349.461616 -69.350162)
						(end 349.483934 -69.29628)
					)
					(arc
						(start 349.483934 -68.96608)
						(mid 349.461616 -68.912198)
						(end 349.407734 -68.88988)
					)
				)
			)
		)
	)
)
